(kicad_pcb
	(version 20260206)
	(generator "pcbnew")
	(generator_version "10.0")
	(general
		(thickness 1.6)
		(legacy_teardrops no)
	)
	(paper "A4")
	(title_block
		(title "01162023_DA0F0TEBIF0_F0T_Expander_BD_F_brd_V02_OCP.brd")
		(comment 1 "Grand Teton / footprints 3870-3876 of 9728")
	)
	(layers
		(0 "F.Cu" signal "TOP")
		(4 "In1.Cu" signal "GND")
		(6 "In2.Cu" signal "VCC")
		(8 "In3.Cu" signal "VCC1")
		(10 "In4.Cu" signal "GND1")
		(12 "In5.Cu" signal "IN1")
		(14 "In6.Cu" signal "GND2")
		(16 "In7.Cu" signal "IN2")
		(18 "In8.Cu" signal "GND3")
		(20 "In9.Cu" signal "IN3")
		(22 "In10.Cu" signal "GND4")
		(24 "In11.Cu" signal "IN4")
		(26 "In12.Cu" signal "GND5")
		(28 "In13.Cu" signal "IN5")
		(30 "In14.Cu" signal "GND6")
		(32 "In15.Cu" signal "IN6")
		(34 "In16.Cu" signal "GND7")
		(2 "B.Cu" signal "BOTTOM")
		(9 "F.Adhes" user "F.Adhesive")
		(11 "B.Adhes" user "B.Adhesive")
		(13 "F.Paste" user "Package Geometry/Pastemask Top")
		(15 "B.Paste" user "Package Geometry/Pastemask Bottom")
		(5 "F.SilkS" user "Ref Des/Silkscreen Top")
		(7 "B.SilkS" user "Ref Des/Silkscreen Bottom")
		(1 "F.Mask" user "Board Geometry/Soldermask Top")
		(3 "B.Mask" user "Board Geometry/Soldermask Bottom")
		(17 "Dwgs.User" user "User.Drawings")
		(19 "Cmts.User" user "User.Comments")
		(21 "Eco1.User" user "User.Eco1")
		(23 "Eco2.User" user "User.Eco2")
		(25 "Edge.Cuts" user "Board Geometry/Outline")
		(27 "Margin" user)
		(31 "F.CrtYd" user "Package Geometry/Place Bound Top")
		(29 "B.CrtYd" user "Package Geometry/Place Bound Bottom")
		(35 "F.Fab" user "Ref Des/Assembly Top")
		(33 "B.Fab" user "Ref Des/Assembly Bottom")
	)
	(footprint ""
		(layer "F.Cu")
		(at 22.263608 -146.592798 -90)
		(property "Reference" "R689"
			(at 0 0 270)
			(layer "F.SilkS")
			(hide yes)
			(effects
				(font
					(size 1.27 1.27)
				)
			)
		)
		(property "Value" ""
			(at 0 0 270)
			(layer "F.Fab")
			(effects
				(font
					(size 1.27 1.27)
				)
			)
		)
		(duplicate_pad_numbers_are_jumpers no)
		(fp_line
			(start -0.7874 0.4064)
			(end -0.7874 -0.4064)
			(stroke
				(width 0.1524)
				(type default)
			)
			(layer "F.SilkS")
		)
		(fp_line
			(start 0.7874 0.4064)
			(end -0.7874 0.4064)
			(stroke
				(width 0.1524)
				(type default)
			)
			(layer "F.SilkS")
		)
		(fp_line
			(start -0.7874 -0.4064)
			(end 0.7874 -0.4064)
			(stroke
				(width 0.1524)
				(type default)
			)
			(layer "F.SilkS")
		)
		(fp_line
			(start 0.7874 -0.4064)
			(end 0.7874 0.4064)
			(stroke
				(width 0.1524)
				(type default)
			)
			(layer "F.SilkS")
		)
		(fp_line
			(start -0.67945 0.3048)
			(end -0.67945 -0.305054)
			(stroke
				(width 0.1)
				(type default)
			)
			(layer "F.Fab")
		)
		(fp_line
			(start -0.12065 0.3048)
			(end -0.67945 0.3048)
			(stroke
				(width 0.1)
				(type default)
			)
			(layer "F.Fab")
		)
		(fp_line
			(start 0.120396 0.3048)
			(end 0.120396 0.2794)
			(stroke
				(width 0.1)
				(type default)
			)
			(layer "F.Fab")
		)
		(fp_line
			(start 0.67945 0.3048)
			(end 0.120396 0.3048)
			(stroke
				(width 0.1)
				(type default)
			)
			(layer "F.Fab")
		)
		(fp_line
			(start -0.12065 0.2794)
			(end -0.12065 0.3048)
			(stroke
				(width 0.1)
				(type default)
			)
			(layer "F.Fab")
		)
		(fp_line
			(start 0.120396 0.2794)
			(end -0.12065 0.2794)
			(stroke
				(width 0.1)
				(type default)
			)
			(layer "F.Fab")
		)
		(fp_line
			(start -0.12065 -0.2794)
			(end 0.12065 -0.2794)
			(stroke
				(width 0.1)
				(type default)
			)
			(layer "F.Fab")
		)
		(fp_line
			(start 0.12065 -0.2794)
			(end 0.12065 -0.3048)
			(stroke
				(width 0.1)
				(type default)
			)
			(layer "F.Fab")
		)
		(fp_line
			(start 0.12065 -0.3048)
			(end 0.67945 -0.3048)
			(stroke
				(width 0.1)
				(type default)
			)
			(layer "F.Fab")
		)
		(fp_line
			(start 0.67945 -0.3048)
			(end 0.67945 0.3048)
			(stroke
				(width 0.1)
				(type default)
			)
			(layer "F.Fab")
		)
		(fp_line
			(start -0.67945 -0.305054)
			(end -0.12065 -0.305054)
			(stroke
				(width 0.1)
				(type default)
			)
			(layer "F.Fab")
		)
		(fp_line
			(start -0.12065 -0.305054)
			(end -0.12065 -0.2794)
			(stroke
				(width 0.1)
				(type default)
			)
			(layer "F.Fab")
		)
		(pad "1" smd circle
			(at -0.40005 0 270)
			(size 0 0)
			(layers "F.Cu" "F.Mask" "F.Paste")
			(net "P12V_NIC0_R")
		)
		(pad "2" smd circle
			(at 0.40005 0 270)
			(size 0 0)
			(layers "F.Cu" "F.Mask" "F.Paste")
			(net "P12V_NIC0_VIN_P")
		)
	)
	(footprint ""
		(layer "F.Cu")
		(at 314.861448 -121.391172 180)
		(property "Reference" "C451"
			(at 0 0 180)
			(layer "F.SilkS")
			(hide yes)
			(effects
				(font
					(size 1.27 1.27)
				)
			)
		)
		(property "Value" ""
			(at 0 0 180)
			(layer "F.Fab")
			(effects
				(font
					(size 1.27 1.27)
				)
			)
		)
		(duplicate_pad_numbers_are_jumpers no)
		(fp_line
			(start 0.299974 0.150114)
			(end -0.299974 0.150114)
			(stroke
				(width 0.1)
				(type default)
			)
			(layer "F.Fab")
		)
		(fp_line
			(start 0.299974 -0.150114)
			(end 0.299974 0.150114)
			(stroke
				(width 0.1)
				(type default)
			)
			(layer "F.Fab")
		)
		(fp_line
			(start -0.299974 0.150114)
			(end -0.299974 -0.150114)
			(stroke
				(width 0.1)
				(type default)
			)
			(layer "F.Fab")
		)
		(fp_line
			(start -0.299974 -0.150114)
			(end 0.299974 -0.150114)
			(stroke
				(width 0.1)
				(type default)
			)
			(layer "F.Fab")
		)
		(pad "1" smd rect
			(at -0.2667 0 180)
			(size 0.3048 0.381)
			(layers "F.Cu" "F.Mask" "F.Paste")
			(net "P5E_PEX2_STN0_TX_DP<1>")
		)
		(pad "2" smd rect
			(at 0.2667 0 180)
			(size 0.3048 0.381)
			(layers "F.Cu" "F.Mask" "F.Paste")
			(net "P5E_PEX2_STN0_TX_C_DP<1>")
		)
	)
	(footprint ""
		(layer "F.Cu")
		(at 441.297822 -296.365168 90)
		(property "Reference" "C2761"
			(at 0 0 90)
			(layer "F.SilkS")
			(hide yes)
			(effects
				(font
					(size 1.27 1.27)
				)
			)
		)
		(property "Value" ""
			(at 0 0 90)
			(layer "F.Fab")
			(effects
				(font
					(size 1.27 1.27)
				)
			)
		)
		(duplicate_pad_numbers_are_jumpers no)
		(fp_line
			(start 0.7874 -0.4064)
			(end 0.7874 0.4064)
			(stroke
				(width 0.1524)
				(type default)
			)
			(layer "F.SilkS")
		)
		(fp_line
			(start -0.7874 -0.4064)
			(end 0.7874 -0.4064)
			(stroke
				(width 0.1524)
				(type default)
			)
			(layer "F.SilkS")
		)
		(fp_line
			(start 0.7874 0.4064)
			(end -0.7874 0.4064)
			(stroke
				(width 0.1524)
				(type default)
			)
			(layer "F.SilkS")
		)
		(fp_line
			(start -0.7874 0.4064)
			(end -0.7874 -0.4064)
			(stroke
				(width 0.1524)
				(type default)
			)
			(layer "F.SilkS")
		)
		(fp_line
			(start -0.12065 -0.305054)
			(end -0.12065 -0.2794)
			(stroke
				(width 0.1)
				(type default)
			)
			(layer "F.Fab")
		)
		(fp_line
			(start -0.67945 -0.305054)
			(end -0.12065 -0.305054)
			(stroke
				(width 0.1)
				(type default)
			)
			(layer "F.Fab")
		)
		(fp_line
			(start 0.67945 -0.3048)
			(end 0.67945 0.3048)
			(stroke
				(width 0.1)
				(type default)
			)
			(layer "F.Fab")
		)
		(fp_line
			(start 0.12065 -0.3048)
			(end 0.67945 -0.3048)
			(stroke
				(width 0.1)
				(type default)
			)
			(layer "F.Fab")
		)
		(fp_line
			(start 0.12065 -0.2794)
			(end 0.12065 -0.3048)
			(stroke
				(width 0.1)
				(type default)
			)
			(layer "F.Fab")
		)
		(fp_line
			(start -0.12065 -0.2794)
			(end 0.12065 -0.2794)
			(stroke
				(width 0.1)
				(type default)
			)
			(layer "F.Fab")
		)
		(fp_line
			(start 0.120396 0.2794)
			(end -0.12065 0.2794)
			(stroke
				(width 0.1)
				(type default)
			)
			(layer "F.Fab")
		)
		(fp_line
			(start -0.12065 0.2794)
			(end -0.12065 0.3048)
			(stroke
				(width 0.1)
				(type default)
			)
			(layer "F.Fab")
		)
		(fp_line
			(start 0.67945 0.3048)
			(end 0.120396 0.3048)
			(stroke
				(width 0.1)
				(type default)
			)
			(layer "F.Fab")
		)
		(fp_line
			(start 0.120396 0.3048)
			(end 0.120396 0.2794)
			(stroke
				(width 0.1)
				(type default)
			)
			(layer "F.Fab")
		)
		(fp_line
			(start -0.12065 0.3048)
			(end -0.67945 0.3048)
			(stroke
				(width 0.1)
				(type default)
			)
			(layer "F.Fab")
		)
		(fp_line
			(start -0.67945 0.3048)
			(end -0.67945 -0.305054)
			(stroke
				(width 0.1)
				(type default)
			)
			(layer "F.Fab")
		)
		(pad "1" smd circle
			(at -0.40005 0 90)
			(size 0 0)
			(layers "F.Cu" "F.Mask" "F.Paste")
			(net "GND")
		)
		(pad "2" smd circle
			(at 0.40005 0 90)
			(size 0 0)
			(layers "F.Cu" "F.Mask" "F.Paste")
			(net "P1V8_PEX")
		)
	)
	(footprint ""
		(layer "F.Cu")
		(at 336.55 -201.168 -90)
		(property "Reference" "R4120"
			(at 0 0 270)
			(layer "F.SilkS")
			(hide yes)
			(effects
				(font
					(size 1.27 1.27)
				)
			)
		)
		(property "Value" ""
			(at 0 0 270)
			(layer "F.Fab")
			(effects
				(font
					(size 1.27 1.27)
				)
			)
		)
		(duplicate_pad_numbers_are_jumpers no)
		(fp_line
			(start -0.7874 0.4064)
			(end -0.7874 -0.4064)
			(stroke
				(width 0.1524)
				(type default)
			)
			(layer "F.SilkS")
		)
		(fp_line
			(start 0.7874 0.4064)
			(end -0.7874 0.4064)
			(stroke
				(width 0.1524)
				(type default)
			)
			(layer "F.SilkS")
		)
		(fp_line
			(start -0.7874 -0.4064)
			(end 0.7874 -0.4064)
			(stroke
				(width 0.1524)
				(type default)
			)
			(layer "F.SilkS")
		)
		(fp_line
			(start 0.7874 -0.4064)
			(end 0.7874 0.4064)
			(stroke
				(width 0.1524)
				(type default)
			)
			(layer "F.SilkS")
		)
		(fp_line
			(start -0.67945 0.3048)
			(end -0.67945 -0.305054)
			(stroke
				(width 0.1)
				(type default)
			)
			(layer "F.Fab")
		)
		(fp_line
			(start -0.12065 0.3048)
			(end -0.67945 0.3048)
			(stroke
				(width 0.1)
				(type default)
			)
			(layer "F.Fab")
		)
		(fp_line
			(start 0.120396 0.3048)
			(end 0.120396 0.2794)
			(stroke
				(width 0.1)
				(type default)
			)
			(layer "F.Fab")
		)
		(fp_line
			(start 0.67945 0.3048)
			(end 0.120396 0.3048)
			(stroke
				(width 0.1)
				(type default)
			)
			(layer "F.Fab")
		)
		(fp_line
			(start -0.12065 0.2794)
			(end -0.12065 0.3048)
			(stroke
				(width 0.1)
				(type default)
			)
			(layer "F.Fab")
		)
		(fp_line
			(start 0.120396 0.2794)
			(end -0.12065 0.2794)
			(stroke
				(width 0.1)
				(type default)
			)
			(layer "F.Fab")
		)
		(fp_line
			(start -0.12065 -0.2794)
			(end 0.12065 -0.2794)
			(stroke
				(width 0.1)
				(type default)
			)
			(layer "F.Fab")
		)
		(fp_line
			(start 0.12065 -0.2794)
			(end 0.12065 -0.3048)
			(stroke
				(width 0.1)
				(type default)
			)
			(layer "F.Fab")
		)
		(fp_line
			(start 0.12065 -0.3048)
			(end 0.67945 -0.3048)
			(stroke
				(width 0.1)
				(type default)
			)
			(layer "F.Fab")
		)
		(fp_line
			(start 0.67945 -0.3048)
			(end 0.67945 0.3048)
			(stroke
				(width 0.1)
				(type default)
			)
			(layer "F.Fab")
		)
		(fp_line
			(start -0.67945 -0.305054)
			(end -0.12065 -0.305054)
			(stroke
				(width 0.1)
				(type default)
			)
			(layer "F.Fab")
		)
		(fp_line
			(start -0.12065 -0.305054)
			(end -0.12065 -0.2794)
			(stroke
				(width 0.1)
				(type default)
			)
			(layer "F.Fab")
		)
		(pad "1" smd circle
			(at -0.40005 0 270)
			(size 0 0)
			(layers "F.Cu" "F.Mask" "F.Paste")
			(net "SSD9_PWRDIS")
		)
		(pad "2" smd circle
			(at 0.40005 0 270)
			(size 0 0)
			(layers "F.Cu" "F.Mask" "F.Paste")
			(net "SSD9_PWRDIS_R")
		)
	)
	(footprint ""
		(layer "F.Cu")
		(at 230.421942 -113.583212 -90)
		(property "Reference" "PC627"
			(at 0 0 270)
			(layer "F.SilkS")
			(hide yes)
			(effects
				(font
					(size 1.27 1.27)
				)
			)
		)
		(property "Value" ""
			(at 0 0 270)
			(layer "F.Fab")
			(effects
				(font
					(size 1.27 1.27)
				)
			)
		)
		(duplicate_pad_numbers_are_jumpers no)
		(fp_line
			(start -0.7874 0.4064)
			(end -0.7874 -0.4064)
			(stroke
				(width 0.1524)
				(type default)
			)
			(layer "F.SilkS")
		)
		(fp_line
			(start 0.7874 0.4064)
			(end -0.7874 0.4064)
			(stroke
				(width 0.1524)
				(type default)
			)
			(layer "F.SilkS")
		)
		(fp_line
			(start -0.7874 -0.4064)
			(end 0.7874 -0.4064)
			(stroke
				(width 0.1524)
				(type default)
			)
			(layer "F.SilkS")
		)
		(fp_line
			(start 0.7874 -0.4064)
			(end 0.7874 0.4064)
			(stroke
				(width 0.1524)
				(type default)
			)
			(layer "F.SilkS")
		)
		(fp_line
			(start -0.67945 0.3048)
			(end -0.67945 -0.305054)
			(stroke
				(width 0.1)
				(type default)
			)
			(layer "F.Fab")
		)
		(fp_line
			(start -0.12065 0.3048)
			(end -0.67945 0.3048)
			(stroke
				(width 0.1)
				(type default)
			)
			(layer "F.Fab")
		)
		(fp_line
			(start 0.120396 0.3048)
			(end 0.120396 0.2794)
			(stroke
				(width 0.1)
				(type default)
			)
			(layer "F.Fab")
		)
		(fp_line
			(start 0.67945 0.3048)
			(end 0.120396 0.3048)
			(stroke
				(width 0.1)
				(type default)
			)
			(layer "F.Fab")
		)
		(fp_line
			(start -0.12065 0.2794)
			(end -0.12065 0.3048)
			(stroke
				(width 0.1)
				(type default)
			)
			(layer "F.Fab")
		)
		(fp_line
			(start 0.120396 0.2794)
			(end -0.12065 0.2794)
			(stroke
				(width 0.1)
				(type default)
			)
			(layer "F.Fab")
		)
		(fp_line
			(start -0.12065 -0.2794)
			(end 0.12065 -0.2794)
			(stroke
				(width 0.1)
				(type default)
			)
			(layer "F.Fab")
		)
		(fp_line
			(start 0.12065 -0.2794)
			(end 0.12065 -0.3048)
			(stroke
				(width 0.1)
				(type default)
			)
			(layer "F.Fab")
		)
		(fp_line
			(start 0.12065 -0.3048)
			(end 0.67945 -0.3048)
			(stroke
				(width 0.1)
				(type default)
			)
			(layer "F.Fab")
		)
		(fp_line
			(start 0.67945 -0.3048)
			(end 0.67945 0.3048)
			(stroke
				(width 0.1)
				(type default)
			)
			(layer "F.Fab")
		)
		(fp_line
			(start -0.67945 -0.305054)
			(end -0.12065 -0.305054)
			(stroke
				(width 0.1)
				(type default)
			)
			(layer "F.Fab")
		)
		(fp_line
			(start -0.12065 -0.305054)
			(end -0.12065 -0.2794)
			(stroke
				(width 0.1)
				(type default)
			)
			(layer "F.Fab")
		)
		(pad "1" smd circle
			(at -0.40005 0 270)
			(size 0 0)
			(layers "F.Cu" "F.Mask" "F.Paste")
			(net "P12V_NIC3_R")
		)
		(pad "2" smd circle
			(at 0.40005 0 270)
			(size 0 0)
			(layers "F.Cu" "F.Mask" "F.Paste")
			(net "GND")
		)
	)
	(footprint ""
		(layer "F.Cu")
		(at 5.744972 -72.156828)
		(property "Reference" "U383"
			(at -3.888994 -1.82118 0)
			(unlocked yes)
			(layer "F.SilkS")
			(effects
				(font
					(size 0.7874 0.5842)
					(thickness 0.1524)
				)
				(justify left)
			)
		)
		(property "Value" ""
			(at 0 0 0)
			(layer "F.Fab")
			(effects
				(font
					(size 1.27 1.27)
				)
			)
		)
		(duplicate_pad_numbers_are_jumpers no)
		(fp_line
			(start -1.3462 -1.1938)
			(end -1.3462 1.1684)
			(stroke
				(width 0.1524)
				(type default)
			)
			(layer "F.SilkS")
		)
		(fp_line
			(start -1.3462 1.1938)
			(end 1.3462 1.1938)
			(stroke
				(width 0.1524)
				(type default)
			)
			(layer "F.SilkS")
		)
		(fp_line
			(start 1.3462 -1.1938)
			(end -1.3462 -1.1938)
			(stroke
				(width 0.1524)
				(type default)
			)
			(layer "F.SilkS")
		)
		(fp_line
			(start 1.3462 1.1938)
			(end 1.3462 -1.1938)
			(stroke
				(width 0.1524)
				(type default)
			)
			(layer "F.SilkS")
		)
		(fp_poly
			(pts
				(xy -1.490218 -0.64135) (xy -2.095246 -0.338836) (xy -2.095246 -0.943864)
			)
			(stroke
				(width 0)
				(type default)
			)
			(fill yes)
			(layer "F.SilkS")
		)
		(fp_line
			(start -0.674878 -1.124966)
			(end -0.674878 1.124966)
			(stroke
				(width 0.1)
				(type default)
			)
			(layer "F.Fab")
		)
		(fp_line
			(start -0.674878 1.124966)
			(end 0.674878 1.124966)
			(stroke
				(width 0.1)
				(type default)
			)
			(layer "F.Fab")
		)
		(fp_line
			(start 0.674878 -1.124966)
			(end -0.674878 -1.124966)
			(stroke
				(width 0.1)
				(type default)
			)
			(layer "F.Fab")
		)
		(fp_line
			(start 0.674878 1.124966)
			(end 0.674878 -1.124966)
			(stroke
				(width 0.1)
				(type default)
			)
			(layer "F.Fab")
		)
		(fp_poly
			(pts
				(xy -1.447038 -0.760476) (xy -2.052066 -0.457962) (xy -2.052066 -1.06299)
			)
			(stroke
				(width 0)
				(type default)
			)
			(fill yes)
			(layer "F.Fab")
		)
		(pad "1" smd rect
			(at -0.899922 -0.750062)
			(size 0.6096 0.6096)
			(layers "F.Cu" "F.Mask" "F.Paste")
			(net "PWRGD_P3V3_SSD0_R")
		)
		(pad "2" smd rect
			(at -0.899922 0 90)
			(size 0.4064 0.6096)
			(layers "F.Cu" "F.Mask" "F.Paste")
			(net "RST_SMB_SSD0_N")
		)
		(pad "3" smd rect
			(at -0.899922 0.750062)
			(size 0.6096 0.6096)
			(layers "F.Cu" "F.Mask" "F.Paste")
			(net "GND")
		)
		(pad "4" smd rect
			(at 0.899922 0.750062)
			(size 0.6096 0.6096)
			(layers "F.Cu" "F.Mask" "F.Paste")
			(net "RST_SMB_SSD0_ISO_N")
		)
		(pad "5" smd rect
			(at 0.899922 -0.750062)
			(size 0.6096 0.6096)
			(layers "F.Cu" "F.Mask" "F.Paste")
			(net "P3V3_AUX")
		)
	)
	(footprint ""
		(layer "F.Cu")
		(at 344.511884 -107.848654 180)
		(property "Reference" "R955"
			(at 0 0 180)
			(layer "F.SilkS")
			(hide yes)
			(effects
				(font
					(size 1.27 1.27)
				)
			)
		)
		(property "Value" ""
			(at 0 0 180)
			(layer "F.Fab")
			(effects
				(font
					(size 1.27 1.27)
				)
			)
		)
		(duplicate_pad_numbers_are_jumpers no)
		(fp_line
			(start 0.7874 0.4064)
			(end -0.7874 0.4064)
			(stroke
				(width 0.1524)
				(type default)
			)
			(layer "F.SilkS")
		)
		(fp_line
			(start 0.7874 -0.4064)
			(end 0.7874 0.4064)
			(stroke
				(width 0.1524)
				(type default)
			)
			(layer "F.SilkS")
		)
		(fp_line
			(start -0.7874 0.4064)
			(end -0.7874 -0.4064)
			(stroke
				(width 0.1524)
				(type default)
			)
			(layer "F.SilkS")
		)
		(fp_line
			(start -0.7874 -0.4064)
			(end 0.7874 -0.4064)
			(stroke
				(width 0.1524)
				(type default)
			)
			(layer "F.SilkS")
		)
		(fp_line
			(start 0.67945 0.3048)
			(end 0.120396 0.3048)
			(stroke
				(width 0.1)
				(type default)
			)
			(layer "F.Fab")
		)
		(fp_line
			(start 0.67945 -0.3048)
			(end 0.67945 0.3048)
			(stroke
				(width 0.1)
				(type default)
			)
			(layer "F.Fab")
		)
		(fp_line
			(start 0.12065 -0.2794)
			(end 0.12065 -0.3048)
			(stroke
				(width 0.1)
				(type default)
			)
			(layer "F.Fab")
		)
		(fp_line
			(start 0.12065 -0.3048)
			(end 0.67945 -0.3048)
			(stroke
				(width 0.1)
				(type default)
			)
			(layer "F.Fab")
		)
		(fp_line
			(start 0.120396 0.3048)
			(end 0.120396 0.2794)
			(stroke
				(width 0.1)
				(type default)
			)
			(layer "F.Fab")
		)
		(fp_line
			(start 0.120396 0.2794)
			(end -0.12065 0.2794)
			(stroke
				(width 0.1)
				(type default)
			)
			(layer "F.Fab")
		)
		(fp_line
			(start -0.12065 0.3048)
			(end -0.67945 0.3048)
			(stroke
				(width 0.1)
				(type default)
			)
			(layer "F.Fab")
		)
		(fp_line
			(start -0.12065 0.2794)
			(end -0.12065 0.3048)
			(stroke
				(width 0.1)
				(type default)
			)
			(layer "F.Fab")
		)
		(fp_line
			(start -0.12065 -0.2794)
			(end 0.12065 -0.2794)
			(stroke
				(width 0.1)
				(type default)
			)
			(layer "F.Fab")
		)
		(fp_line
			(start -0.12065 -0.305054)
			(end -0.12065 -0.2794)
			(stroke
				(width 0.1)
				(type default)
			)
			(layer "F.Fab")
		)
		(fp_line
			(start -0.67945 0.3048)
			(end -0.67945 -0.305054)
			(stroke
				(width 0.1)
				(type default)
			)
			(layer "F.Fab")
		)
		(fp_line
			(start -0.67945 -0.305054)
			(end -0.12065 -0.305054)
			(stroke
				(width 0.1)
				(type default)
			)
			(layer "F.Fab")
		)
		(pad "1" smd circle
			(at -0.40005 0 180)
			(size 0 0)
			(layers "F.Cu" "F.Mask" "F.Paste")
			(net "HP_NIC5_EN")
		)
		(pad "2" smd circle
			(at 0.40005 0 180)
			(size 0 0)
			(layers "F.Cu" "F.Mask" "F.Paste")
			(net "P12V_NIC5_CO_EN")
		)
	)
)
